(kicad_pcb
	(version 20260206)
	(generator "pcbnew")
	(generator_version "10.0")
	(general
		(thickness 1.6)
		(legacy_teardrops no)
	)
	(paper "A4")
	(title_block
		(title "peb — Lightning_PEB_BRD.brd")
		(comment 1 "Lightning (Wiwynn / Facebook NVMe JBOF) / footprints 1162-1167 of 2563")
	)
	(layers
		(0 "F.Cu" signal "TOP")
		(4 "In1.Cu" signal "L2GND")
		(6 "In2.Cu" signal "L3")
		(8 "In3.Cu" signal "L4VCC")
		(10 "In4.Cu" signal "L5VCC")
		(12 "In5.Cu" signal "L6")
		(14 "In6.Cu" signal "L7GND")
		(2 "B.Cu" signal "BOTTOM")
		(9 "F.Adhes" user "F.Adhesive")
		(11 "B.Adhes" user "B.Adhesive")
		(13 "F.Paste" user "Package Geometry/Pastemask Top")
		(15 "B.Paste" user "Package Geometry/Pastemask Bottom")
		(5 "F.SilkS" user "Ref Des/Silkscreen Top")
		(7 "B.SilkS" user "Ref Des/Silkscreen Bottom")
		(1 "F.Mask" user "Board Geometry/Soldermask Top")
		(3 "B.Mask" user "Board Geometry/Soldermask Bottom")
		(17 "Dwgs.User" user "User.Drawings")
		(19 "Cmts.User" user "User.Comments")
		(21 "Eco1.User" user "User.Eco1")
		(23 "Eco2.User" user "User.Eco2")
		(25 "Edge.Cuts" user "Board Geometry/Outline")
		(27 "Margin" user)
		(31 "F.CrtYd" user "Package Geometry/Place Bound Top")
		(29 "B.CrtYd" user "Package Geometry/Place Bound Bottom")
		(35 "F.Fab" user "Ref Des/Assembly Top")
		(33 "B.Fab" user "Ref Des/Assembly Bottom")
	)
	(footprint ""
		(layer "F.Cu")
		(at 74.144124 -189.585092)
		(property "Reference" "U198"
			(at 0 0 0)
			(layer "F.SilkS")
			(hide yes)
			(effects
				(font
					(size 1.27 1.27)
				)
			)
		)
		(property "Value" "MAX7311AUG-GP"
			(at 0 -12.1412 0)
			(unlocked yes)
			(layer "F.Fab")
			(hide yes)
			(effects
				(font
					(size 1.016 1.016)
					(thickness 0.1524)
				)
			)
		)
		(property "Device Type" "TSOIC24H44"
			(at 0 -13.6652 0)
			(unlocked yes)
			(layer "F.Fab")
			(hide yes)
			(effects
				(font
					(size 1.016 1.016)
					(thickness 0.1524)
				)
			)
		)
		(duplicate_pad_numbers_are_jumpers no)
		(fp_line
			(start -4.1148 -1.778)
			(end -4.1148 1.778)
			(stroke
				(width 0.1524)
				(type default)
			)
			(layer "F.SilkS")
		)
		(fp_line
			(start -4.1148 -1.778)
			(end 3.683 -1.778)
			(stroke
				(width 0.1524)
				(type default)
			)
			(layer "F.SilkS")
		)
		(fp_line
			(start -4.0386 1.778)
			(end -4.0386 3.556)
			(stroke
				(width 0.3556)
				(type default)
			)
			(layer "F.SilkS")
		)
		(fp_line
			(start -3.8354 0)
			(end -4.1148 -0.2794)
			(stroke
				(width 0.1524)
				(type default)
			)
			(layer "F.SilkS")
		)
		(fp_line
			(start -3.8354 0)
			(end -4.1148 0.2794)
			(stroke
				(width 0.1524)
				(type default)
			)
			(layer "F.SilkS")
		)
		(fp_line
			(start 3.683 -1.778)
			(end 3.683 1.778)
			(stroke
				(width 0.1524)
				(type default)
			)
			(layer "F.SilkS")
		)
		(fp_line
			(start 3.683 1.778)
			(end -4.1148 1.778)
			(stroke
				(width 0.1524)
				(type default)
			)
			(layer "F.SilkS")
		)
		(fp_poly
			(pts
				(xy -3.7592 -1.778) (xy 3.683 -1.778) (xy 3.683 1.778) (xy -3.7592 1.778)
			)
			(stroke
				(width 0)
				(type default)
			)
			(fill yes)
			(layer "F.SilkS")
		)
		(fp_poly
			(pts
				(xy -4.22656 3.81) (xy 4.22656 3.81) (xy 4.22656 -3.81) (xy -4.22656 -3.81)
			)
			(stroke
				(width 0)
				(type default)
			)
			(fill no)
			(layer "F.CrtYd")
		)
		(fp_poly
			(pts
				(xy -4.22656 -3.81) (xy 4.22656 -3.81) (xy 4.22656 3.81) (xy -4.22656 3.81)
			)
			(stroke
				(width 0)
				(type default)
			)
			(fill no)
			(layer "F.Fab")
		)
		(pad "1" smd rect
			(at -3.57632 2.8194)
			(size 0.3556 1.524)
			(layers "F.Cu" "F.Mask" "F.Paste")
			(net "IOEXP_INT#_1")
		)
		(pad "2" smd rect
			(at -2.92608 2.8194)
			(size 0.3556 1.524)
			(layers "F.Cu" "F.Mask" "F.Paste")
			(net "IOEXP1_AD1")
		)
		(pad "3" smd rect
			(at -2.27584 2.8194)
			(size 0.3556 1.524)
			(layers "F.Cu" "F.Mask" "F.Paste")
			(net "IOEXP1_AD2")
		)
		(pad "4" smd rect
			(at -1.6256 2.8194)
			(size 0.3556 1.524)
			(layers "F.Cu" "F.Mask" "F.Paste")
			(net "SSD_PRSNT#0")
		)
		(pad "5" smd rect
			(at -0.97536 2.8194)
			(size 0.3556 1.524)
			(layers "F.Cu" "F.Mask" "F.Paste")
			(net "SSD_ATNLED#0")
		)
		(pad "6" smd rect
			(at -0.32512 2.8194)
			(size 0.3556 1.524)
			(layers "F.Cu" "F.Mask" "F.Paste")
			(net "SSD_PWREN0")
		)
		(pad "7" smd rect
			(at 0.32512 2.8194)
			(size 0.3556 1.524)
			(layers "F.Cu" "F.Mask" "F.Paste")
			(net "SSD_PERST#0")
		)
		(pad "8" smd rect
			(at 0.97536 2.8194)
			(size 0.3556 1.524)
			(layers "F.Cu" "F.Mask" "F.Paste")
			(net "SSD_PRSNT#5")
		)
		(pad "9" smd rect
			(at 1.6256 2.8194)
			(size 0.3556 1.524)
			(layers "F.Cu" "F.Mask" "F.Paste")
			(net "SSD_ATNLED#5")
		)
		(pad "10" smd rect
			(at 2.27584 2.8194)
			(size 0.3556 1.524)
			(layers "F.Cu" "F.Mask" "F.Paste")
			(net "SSD_PWREN5")
		)
		(pad "11" smd rect
			(at 2.92608 2.8194)
			(size 0.3556 1.524)
			(layers "F.Cu" "F.Mask" "F.Paste")
			(net "SSD_PERST#5")
		)
		(pad "12" smd rect
			(at 3.57632 2.8194)
			(size 0.3556 1.524)
			(layers "F.Cu" "F.Mask" "F.Paste")
			(net "GND")
		)
		(pad "13" smd rect
			(at 3.57632 -2.8194)
			(size 0.3556 1.524)
			(layers "F.Cu" "F.Mask" "F.Paste")
			(net "SSD_PRSNT#10")
		)
		(pad "14" smd rect
			(at 2.92608 -2.8194)
			(size 0.3556 1.524)
			(layers "F.Cu" "F.Mask" "F.Paste")
			(net "SSD_ATNLED#10")
		)
		(pad "15" smd rect
			(at 2.27584 -2.8194)
			(size 0.3556 1.524)
			(layers "F.Cu" "F.Mask" "F.Paste")
			(net "SSD_PWREN10")
		)
		(pad "16" smd rect
			(at 1.6256 -2.8194)
			(size 0.3556 1.524)
			(layers "F.Cu" "F.Mask" "F.Paste")
			(net "SSD_PERST#10")
		)
		(pad "17" smd rect
			(at 0.97536 -2.8194)
			(size 0.3556 1.524)
			(layers "F.Cu" "F.Mask" "F.Paste")
			(net "SSD_PRSNT#11")
		)
		(pad "18" smd rect
			(at 0.32512 -2.8194)
			(size 0.3556 1.524)
			(layers "F.Cu" "F.Mask" "F.Paste")
			(net "SSD_ATNLED#11")
		)
		(pad "19" smd rect
			(at -0.32512 -2.8194)
			(size 0.3556 1.524)
			(layers "F.Cu" "F.Mask" "F.Paste")
			(net "SSD_PWREN11")
		)
		(pad "20" smd rect
			(at -0.97536 -2.8194)
			(size 0.3556 1.524)
			(layers "F.Cu" "F.Mask" "F.Paste")
			(net "SSD_PERST#11")
		)
		(pad "21" smd rect
			(at -1.6256 -2.8194)
			(size 0.3556 1.524)
			(layers "F.Cu" "F.Mask" "F.Paste")
			(net "IOEXP1_AD0")
		)
		(pad "22" smd rect
			(at -2.27584 -2.8194)
			(size 0.3556 1.524)
			(layers "F.Cu" "F.Mask" "F.Paste")
			(net "I2C_GPIO_SCL_1")
		)
		(pad "23" smd rect
			(at -2.92608 -2.8194)
			(size 0.3556 1.524)
			(layers "F.Cu" "F.Mask" "F.Paste")
			(net "I2C_GPIO_SDA_1")
		)
		(pad "24" smd rect
			(at -3.57632 -2.8194)
			(size 0.3556 1.524)
			(layers "F.Cu" "F.Mask" "F.Paste")
			(net "P3V3_STBY")
		)
	)
	(footprint ""
		(layer "F.Cu")
		(at 15.0114 -119.4054 90)
		(property "Reference" "R239"
			(at 0 0 90)
			(layer "F.SilkS")
			(hide yes)
			(effects
				(font
					(size 1.27 1.27)
				)
			)
		)
		(property "Value" "0R2J-2-GP"
			(at 0.064008 -3.993896 90)
			(unlocked yes)
			(layer "F.Fab")
			(hide yes)
			(effects
				(font
					(size 1.016 1.016)
					(thickness 0.1524)
				)
			)
		)
		(property "Device Type" "R402H16"
			(at 0.064008 -5.517896 90)
			(unlocked yes)
			(layer "F.Fab")
			(hide yes)
			(effects
				(font
					(size 1.016 1.016)
					(thickness 0.1524)
				)
			)
		)
		(duplicate_pad_numbers_are_jumpers no)
		(fp_line
			(start 0.508 -0.9398)
			(end -0.508 -0.9398)
			(stroke
				(width 0.1524)
				(type default)
			)
			(layer "F.SilkS")
		)
		(fp_line
			(start -0.508 -0.9398)
			(end -0.508 0.9398)
			(stroke
				(width 0.1524)
				(type default)
			)
			(layer "F.SilkS")
		)
		(fp_rect
			(start -0.508 0.9398)
			(end 0.508 -0.9398)
			(stroke
				(width 0)
				(type default)
			)
			(fill no)
			(layer "F.CrtYd")
		)
		(fp_rect
			(start -0.508 0.9398)
			(end 0.508 -0.9398)
			(stroke
				(width 0)
				(type default)
			)
			(fill no)
			(layer "F.Fab")
		)
		(pad "1" smd custom
			(at 0 -0.4445 90)
			(size 0.1397 0.1397)
			(layers "F.Cu" "F.Mask" "F.Paste")
			(net "BMC_I2C1_MINI1_SDA_S")
			(options
				(clearance outline)
				(anchor circle)
			)
			(primitives
				(gr_poly
					(pts
						(arc
							(start -0.1778 -0.2794)
							(mid -0.249642 -0.249642)
							(end -0.2794 -0.1778)
						)
						(arc
							(start -0.2794 0.1778)
							(mid -0.249642 0.249642)
							(end -0.1778 0.2794)
						)
						(arc
							(start 0.1778 0.2794)
							(mid 0.249642 0.249642)
							(end 0.2794 0.1778)
						)
						(arc
							(start 0.2794 -0.1778)
							(mid 0.249642 -0.249642)
							(end 0.1778 -0.2794)
						)
					)
					(width 0)
					(fill yes)
				)
			)
		)
		(pad "2" smd custom
			(at 0 0.4445 90)
			(size 0.1397 0.1397)
			(layers "F.Cu" "F.Mask" "F.Paste")
			(net "BMC0_SMB1_DAT")
			(options
				(clearance outline)
				(anchor circle)
			)
			(primitives
				(gr_poly
					(pts
						(arc
							(start -0.1778 -0.2794)
							(mid -0.249642 -0.249642)
							(end -0.2794 -0.1778)
						)
						(arc
							(start -0.2794 0.1778)
							(mid -0.249642 0.249642)
							(end -0.1778 0.2794)
						)
						(arc
							(start 0.1778 0.2794)
							(mid 0.249642 0.249642)
							(end 0.2794 0.1778)
						)
						(arc
							(start 0.2794 -0.1778)
							(mid 0.249642 -0.249642)
							(end 0.1778 -0.2794)
						)
					)
					(width 0)
					(fill yes)
				)
			)
		)
	)
	(footprint ""
		(layer "F.Cu")
		(at 28.918154 -146.414744)
		(property "Reference" "C183"
			(at 0 0 0)
			(layer "F.SilkS")
			(hide yes)
			(effects
				(font
					(size 1.27 1.27)
				)
			)
		)
		(property "Value" "SCD1U16V2KX-3GP"
			(at 1.1811 -2.7051 0)
			(unlocked yes)
			(layer "F.Fab")
			(hide yes)
			(effects
				(font
					(size 1.016 1.016)
					(thickness 0.1524)
				)
			)
		)
		(property "Device Type" "C402H22"
			(at 1.1811 -4.2291 0)
			(unlocked yes)
			(layer "F.Fab")
			(hide yes)
			(effects
				(font
					(size 1.016 1.016)
					(thickness 0.1524)
				)
			)
		)
		(duplicate_pad_numbers_are_jumpers no)
		(fp_rect
			(start -0.4318 0.9525)
			(end 0.4318 -0.9525)
			(stroke
				(width 0)
				(type default)
			)
			(fill no)
			(layer "F.CrtYd")
		)
		(fp_rect
			(start -0.4318 0.9525)
			(end 0.4318 -0.9525)
			(stroke
				(width 0)
				(type default)
			)
			(fill no)
			(layer "F.Fab")
		)
		(pad "1" smd custom
			(at 0 -0.4445)
			(size 0.1524 0.1524)
			(layers "F.Cu" "F.Mask" "F.Paste")
			(net "P1V53_STBY")
			(options
				(clearance outline)
				(anchor circle)
			)
			(primitives
				(gr_poly
					(pts
						(arc
							(start 0.3048 -0.2032)
							(mid 0.275042 -0.275042)
							(end 0.2032 -0.3048)
						)
						(arc
							(start -0.2032 -0.3048)
							(mid -0.275042 -0.275042)
							(end -0.3048 -0.2032)
						)
						(arc
							(start -0.3048 0.2032)
							(mid -0.275042 0.275042)
							(end -0.2032 0.3048)
						)
						(arc
							(start 0.2032 0.3048)
							(mid 0.275042 0.275042)
							(end 0.3048 0.2032)
						)
					)
					(width 0)
					(fill yes)
				)
			)
		)
		(pad "2" smd custom
			(at 0 0.4445)
			(size 0.1524 0.1524)
			(layers "F.Cu" "F.Mask" "F.Paste")
			(net "GND")
			(options
				(clearance outline)
				(anchor circle)
			)
			(primitives
				(gr_poly
					(pts
						(arc
							(start 0.3048 -0.2032)
							(mid 0.275042 -0.275042)
							(end 0.2032 -0.3048)
						)
						(arc
							(start -0.2032 -0.3048)
							(mid -0.275042 -0.275042)
							(end -0.3048 -0.2032)
						)
						(arc
							(start -0.3048 0.2032)
							(mid -0.275042 0.275042)
							(end -0.2032 0.3048)
						)
						(arc
							(start 0.2032 0.3048)
							(mid 0.275042 0.275042)
							(end 0.3048 0.2032)
						)
					)
					(width 0)
					(fill yes)
				)
			)
		)
	)
	(footprint ""
		(layer "F.Cu")
		(at 273.517106 -3.57378 -90)
		(property "Reference" "R217"
			(at 0 0 270)
			(layer "F.SilkS")
			(hide yes)
			(effects
				(font
					(size 1.27 1.27)
				)
			)
		)
		(property "Value" "4K7R2F-GP"
			(at 0.064008 -3.993896 270)
			(unlocked yes)
			(layer "F.Fab")
			(hide yes)
			(effects
				(font
					(size 1.016 1.016)
					(thickness 0.1524)
				)
			)
		)
		(property "Device Type" "R402H16"
			(at 0.064008 -5.517896 270)
			(unlocked yes)
			(layer "F.Fab")
			(hide yes)
			(effects
				(font
					(size 1.016 1.016)
					(thickness 0.1524)
				)
			)
		)
		(duplicate_pad_numbers_are_jumpers no)
		(fp_line
			(start -0.508 -0.9398)
			(end -0.508 0.9398)
			(stroke
				(width 0.1524)
				(type default)
			)
			(layer "F.SilkS")
		)
		(fp_line
			(start 0.508 -0.9398)
			(end -0.508 -0.9398)
			(stroke
				(width 0.1524)
				(type default)
			)
			(layer "F.SilkS")
		)
		(fp_rect
			(start -0.508 0.9398)
			(end 0.508 -0.9398)
			(stroke
				(width 0)
				(type default)
			)
			(fill no)
			(layer "F.CrtYd")
		)
		(fp_rect
			(start -0.508 0.9398)
			(end 0.508 -0.9398)
			(stroke
				(width 0)
				(type default)
			)
			(fill no)
			(layer "F.Fab")
		)
		(pad "1" smd custom
			(at 0 -0.4445 270)
			(size 0.1397 0.1397)
			(layers "F.Cu" "F.Mask" "F.Paste")
			(net "CLK_P_6_R")
			(options
				(clearance outline)
				(anchor circle)
			)
			(primitives
				(gr_poly
					(pts
						(arc
							(start -0.1778 -0.2794)
							(mid -0.249642 -0.249642)
							(end -0.2794 -0.1778)
						)
						(arc
							(start -0.2794 0.1778)
							(mid -0.249642 0.249642)
							(end -0.1778 0.2794)
						)
						(arc
							(start 0.1778 0.2794)
							(mid 0.249642 0.249642)
							(end 0.2794 0.1778)
						)
						(arc
							(start 0.2794 -0.1778)
							(mid 0.249642 -0.249642)
							(end 0.1778 -0.2794)
						)
					)
					(width 0)
					(fill yes)
				)
			)
		)
		(pad "2" smd custom
			(at 0 0.4445 270)
			(size 0.1397 0.1397)
			(layers "F.Cu" "F.Mask" "F.Paste")
			(net "GND")
			(options
				(clearance outline)
				(anchor circle)
			)
			(primitives
				(gr_poly
					(pts
						(arc
							(start -0.1778 -0.2794)
							(mid -0.249642 -0.249642)
							(end -0.2794 -0.1778)
						)
						(arc
							(start -0.2794 0.1778)
							(mid -0.249642 0.249642)
							(end -0.1778 0.2794)
						)
						(arc
							(start 0.1778 0.2794)
							(mid 0.249642 0.249642)
							(end 0.2794 0.1778)
						)
						(arc
							(start 0.2794 -0.1778)
							(mid 0.249642 -0.249642)
							(end 0.1778 -0.2794)
						)
					)
					(width 0)
					(fill yes)
				)
			)
		)
	)
	(footprint ""
		(layer "F.Cu")
		(at 29.911294 -94.184724 180)
		(property "Reference" "R2944"
			(at 0 0 180)
			(layer "F.SilkS")
			(hide yes)
			(effects
				(font
					(size 1.27 1.27)
				)
			)
		)
		(property "Value" "4K75R2F-1-GP"
			(at 0.064008 -3.993896 180)
			(unlocked yes)
			(layer "F.Fab")
			(hide yes)
			(effects
				(font
					(size 1.016 1.016)
					(thickness 0.1524)
				)
			)
		)
		(property "Device Type" "R402H16"
			(at 0.064008 -5.517896 180)
			(unlocked yes)
			(layer "F.Fab")
			(hide yes)
			(effects
				(font
					(size 1.016 1.016)
					(thickness 0.1524)
				)
			)
		)
		(duplicate_pad_numbers_are_jumpers no)
		(fp_line
			(start 0.508 -0.9398)
			(end -0.508 -0.9398)
			(stroke
				(width 0.1524)
				(type default)
			)
			(layer "F.SilkS")
		)
		(fp_line
			(start -0.508 -0.9398)
			(end -0.508 0.9398)
			(stroke
				(width 0.1524)
				(type default)
			)
			(layer "F.SilkS")
		)
		(fp_rect
			(start -0.508 0.9398)
			(end 0.508 -0.9398)
			(stroke
				(width 0)
				(type default)
			)
			(fill no)
			(layer "F.CrtYd")
		)
		(fp_rect
			(start -0.508 0.9398)
			(end 0.508 -0.9398)
			(stroke
				(width 0)
				(type default)
			)
			(fill no)
			(layer "F.Fab")
		)
		(pad "1" smd custom
			(at 0 -0.4445 180)
			(size 0.1397 0.1397)
			(layers "F.Cu" "F.Mask" "F.Paste")
			(net "P3V3_STBY")
			(options
				(clearance outline)
				(anchor circle)
			)
			(primitives
				(gr_poly
					(pts
						(arc
							(start -0.1778 -0.2794)
							(mid -0.249642 -0.249642)
							(end -0.2794 -0.1778)
						)
						(arc
							(start -0.2794 0.1778)
							(mid -0.249642 0.249642)
							(end -0.1778 0.2794)
						)
						(arc
							(start 0.1778 0.2794)
							(mid 0.249642 0.249642)
							(end 0.2794 0.1778)
						)
						(arc
							(start 0.2794 -0.1778)
							(mid 0.249642 -0.249642)
							(end 0.1778 -0.2794)
						)
					)
					(width 0)
					(fill yes)
				)
			)
		)
		(pad "2" smd custom
			(at 0 0.4445 180)
			(size 0.1397 0.1397)
			(layers "F.Cu" "F.Mask" "F.Paste")
			(net "RST_BMC_EXTRST_N")
			(options
				(clearance outline)
				(anchor circle)
			)
			(primitives
				(gr_poly
					(pts
						(arc
							(start -0.1778 -0.2794)
							(mid -0.249642 -0.249642)
							(end -0.2794 -0.1778)
						)
						(arc
							(start -0.2794 0.1778)
							(mid -0.249642 0.249642)
							(end -0.1778 0.2794)
						)
						(arc
							(start 0.1778 0.2794)
							(mid 0.249642 0.249642)
							(end 0.2794 0.1778)
						)
						(arc
							(start 0.2794 -0.1778)
							(mid 0.249642 -0.249642)
							(end 0.1778 -0.2794)
						)
					)
					(width 0)
					(fill yes)
				)
			)
		)
	)
	(footprint ""
		(layer "F.Cu")
		(at 30.48 -196.85 -90)
		(property "Reference" "R2115"
			(at 0 0 270)
			(layer "F.SilkS")
			(hide yes)
			(effects
				(font
					(size 1.27 1.27)
				)
			)
		)
		(property "Value" "0R2J-2-GP"
			(at 0.064008 -3.993896 270)
			(unlocked yes)
			(layer "F.Fab")
			(hide yes)
			(effects
				(font
					(size 1.016 1.016)
					(thickness 0.1524)
				)
			)
		)
		(property "Device Type" "R402H16"
			(at 0.064008 -5.517896 270)
			(unlocked yes)
			(layer "F.Fab")
			(hide yes)
			(effects
				(font
					(size 1.016 1.016)
					(thickness 0.1524)
				)
			)
		)
		(duplicate_pad_numbers_are_jumpers no)
		(fp_line
			(start -0.508 -0.9398)
			(end -0.508 0.9398)
			(stroke
				(width 0.1524)
				(type default)
			)
			(layer "F.SilkS")
		)
		(fp_line
			(start 0.508 -0.9398)
			(end -0.508 -0.9398)
			(stroke
				(width 0.1524)
				(type default)
			)
			(layer "F.SilkS")
		)
		(fp_rect
			(start -0.508 0.9398)
			(end 0.508 -0.9398)
			(stroke
				(width 0)
				(type default)
			)
			(fill no)
			(layer "F.CrtYd")
		)
		(fp_rect
			(start -0.508 0.9398)
			(end 0.508 -0.9398)
			(stroke
				(width 0)
				(type default)
			)
			(fill no)
			(layer "F.Fab")
		)
		(pad "1" smd custom
			(at 0 -0.4445 270)
			(size 0.1397 0.1397)
			(layers "F.Cu" "F.Mask" "F.Paste")
			(net "MB0_P12V_R")
			(options
				(clearance outline)
				(anchor circle)
			)
			(primitives
				(gr_poly
					(pts
						(arc
							(start -0.1778 -0.2794)
							(mid -0.249642 -0.249642)
							(end -0.2794 -0.1778)
						)
						(arc
							(start -0.2794 0.1778)
							(mid -0.249642 0.249642)
							(end -0.1778 0.2794)
						)
						(arc
							(start 0.1778 0.2794)
							(mid 0.249642 0.249642)
							(end 0.2794 0.1778)
						)
						(arc
							(start 0.2794 -0.1778)
							(mid 0.249642 -0.249642)
							(end 0.1778 -0.2794)
						)
					)
					(width 0)
					(fill yes)
				)
			)
		)
		(pad "2" smd custom
			(at 0 0.4445 270)
			(size 0.1397 0.1397)
			(layers "F.Cu" "F.Mask" "F.Paste")
			(net "P12V")
			(options
				(clearance outline)
				(anchor circle)
			)
			(primitives
				(gr_poly
					(pts
						(arc
							(start -0.1778 -0.2794)
							(mid -0.249642 -0.249642)
							(end -0.2794 -0.1778)
						)
						(arc
							(start -0.2794 0.1778)
							(mid -0.249642 0.249642)
							(end -0.1778 0.2794)
						)
						(arc
							(start 0.1778 0.2794)
							(mid 0.249642 0.249642)
							(end 0.2794 0.1778)
						)
						(arc
							(start 0.2794 -0.1778)
							(mid 0.249642 -0.249642)
							(end 0.1778 -0.2794)
						)
					)
					(width 0)
					(fill yes)
				)
			)
		)
	)
)
